(kicad_pcb
	(version 20260206)
	(generator "pcbnew")
	(generator_version "10.0")
	(general
		(thickness 1.6)
		(legacy_teardrops no)
	)
	(paper "A4")
	(title_block
		(title "v1-chassis-manager — T6M_CM_d_v01_1031_1645.brd")
		(comment 1 "Open CloudServer (Microsoft) / footprints 425-432 of 2512")
	)
	(layers
		(0 "F.Cu" signal "TOP")
		(4 "In1.Cu" signal "GND1")
		(6 "In2.Cu" signal "IN1")
		(8 "In3.Cu" signal "VCC1")
		(10 "In4.Cu" signal "VCC2")
		(12 "In5.Cu" signal "GND2")
		(14 "In6.Cu" signal "IN2")
		(16 "In7.Cu" signal "IN3")
		(18 "In8.Cu" signal "GND3")
		(2 "B.Cu" signal "BOTTOM")
		(9 "F.Adhes" user "F.Adhesive")
		(11 "B.Adhes" user "B.Adhesive")
		(13 "F.Paste" user "Package Geometry/Pastemask Top")
		(15 "B.Paste" user "Package Geometry/Pastemask Bottom")
		(5 "F.SilkS" user "Ref Des/Silkscreen Top")
		(7 "B.SilkS" user "Ref Des/Silkscreen Bottom")
		(1 "F.Mask" user "Board Geometry/Soldermask Top")
		(3 "B.Mask" user "Board Geometry/Soldermask Bottom")
		(17 "Dwgs.User" user "User.Drawings")
		(19 "Cmts.User" user "User.Comments")
		(21 "Eco1.User" user "User.Eco1")
		(23 "Eco2.User" user "User.Eco2")
		(25 "Edge.Cuts" user "Board Geometry/Outline")
		(27 "Margin" user)
		(31 "F.CrtYd" user "Package Geometry/Place Bound Top")
		(29 "B.CrtYd" user "Package Geometry/Place Bound Bottom")
		(35 "F.Fab" user "Ref Des/Assembly Top")
		(33 "B.Fab" user "Ref Des/Assembly Bottom")
	)
	(footprint ""
		(layer "F.Cu")
		(at 151.62276 -185.205624 90)
		(property "Reference" "C744"
			(at 4.768088 0.250952 90)
			(unlocked yes)
			(layer "F.SilkS")
			(effects
				(font
					(size 0.7874 0.5842)
					(thickness 0.1524)
				)
				(justify left)
			)
		)
		(property "Value" ""
			(at 0 0 90)
			(layer "F.Fab")
			(effects
				(font
					(size 1.27 1.27)
				)
			)
		)
		(duplicate_pad_numbers_are_jumpers no)
		(fp_line
			(start 0.7874 -0.4064)
			(end 0.7874 0.4064)
			(stroke
				(width 0.1524)
				(type default)
			)
			(layer "F.SilkS")
		)
		(fp_line
			(start -0.7874 -0.4064)
			(end 0.7874 -0.4064)
			(stroke
				(width 0.1524)
				(type default)
			)
			(layer "F.SilkS")
		)
		(fp_line
			(start 0 0.381)
			(end 0 -0.381)
			(stroke
				(width 0.1524)
				(type default)
			)
			(layer "F.SilkS")
		)
		(fp_line
			(start 0.7874 0.4064)
			(end -0.7874 0.4064)
			(stroke
				(width 0.1524)
				(type default)
			)
			(layer "F.SilkS")
		)
		(fp_line
			(start -0.7874 0.4064)
			(end -0.7874 -0.4064)
			(stroke
				(width 0.1524)
				(type default)
			)
			(layer "F.SilkS")
		)
		(fp_poly
			(pts
				(xy -0.5334 0.254) (xy -0.635 0.254) (xy -0.635 0.2286) (xy -0.635 -0.254) (xy -0.5334 -0.254) (xy -0.5334 -0.2794)
				(xy 0.5334 -0.2794) (xy 0.5334 -0.254) (xy 0.635 -0.254) (xy 0.635 0.254) (xy 0.5334 0.254) (xy 0.5334 0.2794)
				(xy -0.508 0.2794) (xy -0.5334 0.2794)
			)
			(stroke
				(width 0)
				(type default)
			)
			(fill no)
			(layer "F.CrtYd")
		)
		(pad "1" smd rect
			(at 0.40005 0 90)
			(size 0.4572 0.508)
			(layers "F.Cu" "F.Mask" "F.Paste")
			(net "UART_T12_NODE1_RXD")
		)
		(pad "2" smd rect
			(at -0.40005 0 90)
			(size 0.4572 0.508)
			(layers "F.Cu" "F.Mask" "F.Paste")
			(net "GND")
		)
	)
	(footprint ""
		(layer "F.Cu")
		(at 104.660446 -18.264124 180)
		(property "Reference" "C141"
			(at -1.324864 -1.218946 0)
			(unlocked yes)
			(layer "F.SilkS")
			(effects
				(font
					(size 0.7874 0.5842)
					(thickness 0.1524)
				)
			)
		)
		(property "Value" ""
			(at 0 0 180)
			(layer "F.Fab")
			(effects
				(font
					(size 1.27 1.27)
				)
			)
		)
		(duplicate_pad_numbers_are_jumpers no)
		(fp_line
			(start 1.2954 0.5842)
			(end -1.2954 0.5842)
			(stroke
				(width 0.1524)
				(type default)
			)
			(layer "F.SilkS")
		)
		(fp_line
			(start 1.2954 -0.5842)
			(end 1.2954 0.5842)
			(stroke
				(width 0.1524)
				(type default)
			)
			(layer "F.SilkS")
		)
		(fp_line
			(start 0 -0.5842)
			(end 0 0.5842)
			(stroke
				(width 0.1524)
				(type default)
			)
			(layer "F.SilkS")
		)
		(fp_line
			(start -1.2954 0.5842)
			(end -1.2954 -0.5842)
			(stroke
				(width 0.1524)
				(type default)
			)
			(layer "F.SilkS")
		)
		(fp_line
			(start -1.2954 -0.5842)
			(end 1.2954 -0.5842)
			(stroke
				(width 0.1524)
				(type default)
			)
			(layer "F.SilkS")
		)
		(fp_poly
			(pts
				(xy 0.8636 -0.4572) (xy 0.8636 -0.3556) (xy 1.143 -0.3556) (xy 1.143 0.3556) (xy 0.8636 0.3556)
				(xy 0.8636 0.4572) (xy -0.8636 0.4572) (xy -0.8636 0.3556) (xy -1.143 0.3556) (xy -1.143 -0.3556)
				(xy -0.8636 -0.3556) (xy -0.8636 -0.4572)
			)
			(stroke
				(width 0)
				(type default)
			)
			(fill no)
			(layer "F.CrtYd")
		)
		(fp_line
			(start 0.884936 0.504952)
			(end -0.884936 0.504952)
			(stroke
				(width 0.1)
				(type default)
			)
			(layer "F.Fab")
		)
		(fp_line
			(start 0.884936 -0.504952)
			(end 0.884936 0.504952)
			(stroke
				(width 0.1)
				(type default)
			)
			(layer "F.Fab")
		)
		(fp_line
			(start -0.884936 0.504952)
			(end -0.884936 -0.504952)
			(stroke
				(width 0.1)
				(type default)
			)
			(layer "F.Fab")
		)
		(fp_line
			(start -0.884936 -0.504952)
			(end 0.884936 -0.504952)
			(stroke
				(width 0.1)
				(type default)
			)
			(layer "F.Fab")
		)
		(pad "1" smd rect
			(at 0.7366 0 270)
			(size 0.7112 0.8128)
			(layers "F.Cu" "F.Mask" "F.Paste")
			(net "PV_VTT_DDR_NODE1")
		)
		(pad "2" smd rect
			(at -0.7366 0 270)
			(size 0.7112 0.8128)
			(layers "F.Cu" "F.Mask" "F.Paste")
			(net "GND")
		)
	)
	(footprint ""
		(layer "F.Cu")
		(at 149.57806 -30.946344)
		(property "Reference" "C530"
			(at -1.312164 2.11709 0)
			(unlocked yes)
			(layer "F.SilkS")
			(effects
				(font
					(size 0.7874 0.5842)
					(thickness 0.1524)
				)
				(justify left)
			)
		)
		(property "Value" ""
			(at 0 0 0)
			(layer "F.Fab")
			(effects
				(font
					(size 1.27 1.27)
				)
			)
		)
		(duplicate_pad_numbers_are_jumpers no)
		(fp_line
			(start -0.7874 -0.4064)
			(end 0.7874 -0.4064)
			(stroke
				(width 0.1524)
				(type default)
			)
			(layer "F.SilkS")
		)
		(fp_line
			(start -0.7874 0.4064)
			(end -0.7874 -0.4064)
			(stroke
				(width 0.1524)
				(type default)
			)
			(layer "F.SilkS")
		)
		(fp_line
			(start 0 0.381)
			(end 0 -0.381)
			(stroke
				(width 0.1524)
				(type default)
			)
			(layer "F.SilkS")
		)
		(fp_line
			(start 0.7874 -0.4064)
			(end 0.7874 0.4064)
			(stroke
				(width 0.1524)
				(type default)
			)
			(layer "F.SilkS")
		)
		(fp_line
			(start 0.7874 0.4064)
			(end -0.7874 0.4064)
			(stroke
				(width 0.1524)
				(type default)
			)
			(layer "F.SilkS")
		)
		(fp_poly
			(pts
				(xy -0.5334 0.254) (xy -0.635 0.254) (xy -0.635 0.2286) (xy -0.635 -0.254) (xy -0.5334 -0.254) (xy -0.5334 -0.2794)
				(xy 0.5334 -0.2794) (xy 0.5334 -0.254) (xy 0.635 -0.254) (xy 0.635 0.254) (xy 0.5334 0.254) (xy 0.5334 0.2794)
				(xy -0.508 0.2794) (xy -0.5334 0.2794)
			)
			(stroke
				(width 0)
				(type default)
			)
			(fill no)
			(layer "F.CrtYd")
		)
		(pad "1" smd rect
			(at 0.40005 0)
			(size 0.4572 0.508)
			(layers "F.Cu" "F.Mask" "F.Paste")
			(net "P3V3_NODE1")
		)
		(pad "2" smd rect
			(at -0.40005 0)
			(size 0.4572 0.508)
			(layers "F.Cu" "F.Mask" "F.Paste")
			(net "GND")
		)
	)
	(footprint ""
		(layer "F.Cu")
		(at 148.79447 -51.893724 90)
		(property "Reference" "C496"
			(at 17.456658 27.329892 90)
			(unlocked yes)
			(layer "F.SilkS")
			(effects
				(font
					(size 0.7874 0.5842)
					(thickness 0.1524)
				)
			)
		)
		(property "Value" ""
			(at 0 0 90)
			(layer "F.Fab")
			(effects
				(font
					(size 1.27 1.27)
				)
			)
		)
		(duplicate_pad_numbers_are_jumpers no)
		(fp_line
			(start 1.2954 -0.5842)
			(end 1.2954 0.5842)
			(stroke
				(width 0.1524)
				(type default)
			)
			(layer "F.SilkS")
		)
		(fp_line
			(start 0 -0.5842)
			(end 0 0.5842)
			(stroke
				(width 0.1524)
				(type default)
			)
			(layer "F.SilkS")
		)
		(fp_line
			(start -1.2954 -0.5842)
			(end 1.2954 -0.5842)
			(stroke
				(width 0.1524)
				(type default)
			)
			(layer "F.SilkS")
		)
		(fp_line
			(start 1.2954 0.5842)
			(end -1.2954 0.5842)
			(stroke
				(width 0.1524)
				(type default)
			)
			(layer "F.SilkS")
		)
		(fp_line
			(start -1.2954 0.5842)
			(end -1.2954 -0.5842)
			(stroke
				(width 0.1524)
				(type default)
			)
			(layer "F.SilkS")
		)
		(fp_poly
			(pts
				(xy 0.8636 -0.4572) (xy 0.8636 -0.3556) (xy 1.143 -0.3556) (xy 1.143 0.3556) (xy 0.8636 0.3556)
				(xy 0.8636 0.4572) (xy -0.8636 0.4572) (xy -0.8636 0.3556) (xy -1.143 0.3556) (xy -1.143 -0.3556)
				(xy -0.8636 -0.3556) (xy -0.8636 -0.4572)
			)
			(stroke
				(width 0)
				(type default)
			)
			(fill no)
			(layer "F.CrtYd")
		)
		(fp_line
			(start 0.884936 -0.504952)
			(end 0.884936 0.504952)
			(stroke
				(width 0.1)
				(type default)
			)
			(layer "F.Fab")
		)
		(fp_line
			(start -0.884936 -0.504952)
			(end 0.884936 -0.504952)
			(stroke
				(width 0.1)
				(type default)
			)
			(layer "F.Fab")
		)
		(fp_line
			(start 0.884936 0.504952)
			(end -0.884936 0.504952)
			(stroke
				(width 0.1)
				(type default)
			)
			(layer "F.Fab")
		)
		(fp_line
			(start -0.884936 0.504952)
			(end -0.884936 -0.504952)
			(stroke
				(width 0.1)
				(type default)
			)
			(layer "F.Fab")
		)
		(pad "1" smd rect
			(at 0.7366 0 180)
			(size 0.7112 0.8128)
			(layers "F.Cu" "F.Mask" "F.Paste")
			(net "SATA_P7")
		)
		(pad "2" smd rect
			(at -0.7366 0 180)
			(size 0.7112 0.8128)
			(layers "F.Cu" "F.Mask" "F.Paste")
			(net "GND")
		)
	)
	(footprint ""
		(layer "F.Cu")
		(at 51.748182 -173.527466 180)
		(property "Reference" "U85"
			(at 3.621278 -133.039612 90)
			(unlocked yes)
			(layer "F.SilkS")
			(effects
				(font
					(size 0.7874 0.5842)
					(thickness 0.1524)
				)
				(justify left)
			)
		)
		(property "Value" ""
			(at 0 0 180)
			(layer "F.Fab")
			(effects
				(font
					(size 1.27 1.27)
				)
			)
		)
		(duplicate_pad_numbers_are_jumpers no)
		(fp_line
			(start 1.549908 2.032)
			(end -1.549908 2.032)
			(stroke
				(width 0.1524)
				(type default)
			)
			(layer "F.SilkS")
		)
		(fp_line
			(start 1.549908 -2.032)
			(end 1.549908 2.032)
			(stroke
				(width 0.1524)
				(type default)
			)
			(layer "F.SilkS")
		)
		(fp_line
			(start -1.549908 2.032)
			(end -1.549908 -2.032)
			(stroke
				(width 0.1524)
				(type default)
			)
			(layer "F.SilkS")
		)
		(fp_line
			(start -1.549908 -2.032)
			(end 1.549908 -2.032)
			(stroke
				(width 0.1524)
				(type default)
			)
			(layer "F.SilkS")
		)
		(fp_poly
			(pts
				(xy -2.9464 1.016) (xy -2.9464 1.524) (xy -2.1844 1.27)
			)
			(stroke
				(width 0)
				(type default)
			)
			(fill yes)
			(layer "F.SilkS")
		)
		(fp_poly
			(pts
				(xy -1.549908 0.849884) (xy -1.2319 0.849884) (xy -1.2319 1.9431) (xy -1.1811 1.9431) (xy 1.1811 1.9431)
				(xy 1.2319 1.9431) (xy 1.2319 0.849884) (xy 1.549908 0.849884) (xy 1.549908 -0.849884) (xy 1.2319 -0.849884)
				(xy 1.2319 -1.9431) (xy 1.1811 -1.9431) (xy -1.1811 -1.9431) (xy -1.2319 -1.9431) (xy -1.2319 -0.849884)
				(xy -1.549908 -0.849884)
			)
			(stroke
				(width 0)
				(type default)
			)
			(fill no)
			(layer "F.CrtYd")
		)
		(fp_line
			(start 1.549908 0.849884)
			(end 1.549908 -0.849884)
			(stroke
				(width 0.1)
				(type default)
			)
			(layer "F.Fab")
		)
		(fp_line
			(start 1.549908 -0.849884)
			(end -1.549908 -0.849884)
			(stroke
				(width 0.1)
				(type default)
			)
			(layer "F.Fab")
		)
		(fp_line
			(start -1.549908 0.849884)
			(end 1.549908 0.849884)
			(stroke
				(width 0.1)
				(type default)
			)
			(layer "F.Fab")
		)
		(fp_line
			(start -1.549908 -0.849884)
			(end -1.549908 0.849884)
			(stroke
				(width 0.1)
				(type default)
			)
			(layer "F.Fab")
		)
		(fp_text user "3"
			(at 1.21793 2.684526 0)
			(unlocked yes)
			(layer "F.SilkS")
			(effects
				(font
					(size 0.635 0.4064)
					(thickness 0.1524)
				)
				(justify left)
			)
		)
		(fp_text user "4"
			(at 0.991108 -2.59334 0)
			(unlocked yes)
			(layer "F.SilkS")
			(effects
				(font
					(size 0.635 0.4064)
					(thickness 0.1524)
				)
				(justify left)
			)
		)
		(fp_text user "1"
			(at -0.14224 2.492248 0)
			(unlocked yes)
			(layer "F.SilkS")
			(effects
				(font
					(size 0.635 0.4064)
					(thickness 0.1524)
				)
				(justify left)
			)
		)
		(fp_text user "5"
			(at -1.83261 -2.563368 0)
			(unlocked yes)
			(layer "F.SilkS")
			(effects
				(font
					(size 0.635 0.4064)
					(thickness 0.1524)
				)
				(justify left)
			)
		)
		(pad "1" smd rect
			(at -0.94996 1.225042 180)
			(size 0.4572 1.3208)
			(layers "F.Cu" "F.Mask" "F.Paste")
			(net "Net_1706")
		)
		(pad "2" smd rect
			(at 0 1.225042 180)
			(size 0.4572 1.3208)
			(layers "F.Cu" "F.Mask" "F.Paste")
			(net "PSU5_DC_OK_R_BUF")
		)
		(pad "3" smd rect
			(at 0.94996 1.225042 180)
			(size 0.4572 1.3208)
			(layers "F.Cu" "F.Mask" "F.Paste")
			(net "GND")
		)
		(pad "4" smd rect
			(at 0.94996 -1.225042 180)
			(size 0.4572 1.3208)
			(layers "F.Cu" "F.Mask" "F.Paste")
			(net "PSU5_DC_OK")
		)
		(pad "5" smd rect
			(at -0.94996 -1.225042 180)
			(size 0.4572 1.3208)
			(layers "F.Cu" "F.Mask" "F.Paste")
			(net "P3V3_NODE1")
		)
	)
	(footprint ""
		(layer "F.Cu")
		(at 135.255 -51.435 90)
		(property "Reference" "R614"
			(at 16.3576 30.65907 90)
			(unlocked yes)
			(layer "F.SilkS")
			(effects
				(font
					(size 0.7874 0.5842)
					(thickness 0.1524)
				)
				(justify left)
			)
		)
		(property "Value" ""
			(at 0 0 90)
			(layer "F.Fab")
			(effects
				(font
					(size 1.27 1.27)
				)
			)
		)
		(duplicate_pad_numbers_are_jumpers no)
		(fp_line
			(start 0.7874 -0.4064)
			(end 0.7874 0.4064)
			(stroke
				(width 0.1524)
				(type default)
			)
			(layer "F.SilkS")
		)
		(fp_line
			(start -0.7874 -0.4064)
			(end 0.7874 -0.4064)
			(stroke
				(width 0.1524)
				(type default)
			)
			(layer "F.SilkS")
		)
		(fp_line
			(start 0.7874 0.4064)
			(end -0.7874 0.4064)
			(stroke
				(width 0.1524)
				(type default)
			)
			(layer "F.SilkS")
		)
		(fp_line
			(start -0.7874 0.4064)
			(end -0.7874 -0.4064)
			(stroke
				(width 0.1524)
				(type default)
			)
			(layer "F.SilkS")
		)
		(fp_poly
			(pts
				(xy -0.508 0.2794) (xy -0.508 0.2286) (xy -0.635 0.2286) (xy -0.635 -0.254) (xy -0.5334 -0.254)
				(xy -0.5334 -0.2794) (xy 0.5334 -0.2794) (xy 0.5334 -0.254) (xy 0.635 -0.254) (xy 0.635 0.254) (xy 0.5334 0.254)
				(xy 0.5334 0.2794)
			)
			(stroke
				(width 0)
				(type default)
			)
			(fill no)
			(layer "F.CrtYd")
		)
		(pad "1" smd rect
			(at 0.40005 0 90)
			(size 0.4572 0.508)
			(layers "F.Cu" "F.Mask" "F.Paste")
			(net "P5V_NODE1")
		)
		(pad "2" smd rect
			(at -0.40005 0 90)
			(size 0.4572 0.508)
			(layers "F.Cu" "F.Mask" "F.Paste")
			(net "UART_DSR_P3_N")
		)
	)
	(footprint ""
		(layer "F.Cu")
		(at 111.696246 -129.847848 90)
		(property "Reference" "PC95"
			(at -1.715008 -0.91694 90)
			(unlocked yes)
			(layer "F.SilkS")
			(effects
				(font
					(size 0.7874 0.5842)
					(thickness 0.1524)
				)
				(justify left)
			)
		)
		(property "Value" ""
			(at 0 0 90)
			(layer "F.Fab")
			(effects
				(font
					(size 1.27 1.27)
				)
			)
		)
		(duplicate_pad_numbers_are_jumpers no)
		(fp_line
			(start 0.7874 -0.4064)
			(end 0.7874 0.4064)
			(stroke
				(width 0.1524)
				(type default)
			)
			(layer "F.SilkS")
		)
		(fp_line
			(start -0.7874 -0.4064)
			(end 0.7874 -0.4064)
			(stroke
				(width 0.1524)
				(type default)
			)
			(layer "F.SilkS")
		)
		(fp_line
			(start 0 0.381)
			(end 0 -0.381)
			(stroke
				(width 0.1524)
				(type default)
			)
			(layer "F.SilkS")
		)
		(fp_line
			(start 0.7874 0.4064)
			(end -0.7874 0.4064)
			(stroke
				(width 0.1524)
				(type default)
			)
			(layer "F.SilkS")
		)
		(fp_line
			(start -0.7874 0.4064)
			(end -0.7874 -0.4064)
			(stroke
				(width 0.1524)
				(type default)
			)
			(layer "F.SilkS")
		)
		(fp_poly
			(pts
				(xy -0.5334 0.254) (xy -0.635 0.254) (xy -0.635 0.2286) (xy -0.635 -0.254) (xy -0.5334 -0.254) (xy -0.5334 -0.2794)
				(xy 0.5334 -0.2794) (xy 0.5334 -0.254) (xy 0.635 -0.254) (xy 0.635 0.254) (xy 0.5334 0.254) (xy 0.5334 0.2794)
				(xy -0.508 0.2794) (xy -0.5334 0.2794)
			)
			(stroke
				(width 0)
				(type default)
			)
			(fill no)
			(layer "F.CrtYd")
		)
		(pad "1" smd rect
			(at 0.40005 0 90)
			(size 0.4572 0.508)
			(layers "F.Cu" "F.Mask" "F.Paste")
			(net "VR_PVCCP_NODE1_TONSET_R")
		)
		(pad "2" smd rect
			(at -0.40005 0 90)
			(size 0.4572 0.508)
			(layers "F.Cu" "F.Mask" "F.Paste")
			(net "AGND_PVCCP_NODE1")
		)
	)
	(footprint ""
		(layer "F.Cu")
		(at 9.782048 -154.46375)
		(property "Reference" "C550"
			(at 8.409432 5.435854 90)
			(unlocked yes)
			(layer "F.SilkS")
			(effects
				(font
					(size 0.7874 0.5842)
					(thickness 0.1524)
				)
				(justify left)
			)
		)
		(property "Value" ""
			(at 0 0 0)
			(layer "F.Fab")
			(effects
				(font
					(size 1.27 1.27)
				)
			)
		)
		(duplicate_pad_numbers_are_jumpers no)
		(fp_line
			(start -0.7874 -0.4064)
			(end 0.7874 -0.4064)
			(stroke
				(width 0.1524)
				(type default)
			)
			(layer "F.SilkS")
		)
		(fp_line
			(start -0.7874 0.4064)
			(end -0.7874 -0.4064)
			(stroke
				(width 0.1524)
				(type default)
			)
			(layer "F.SilkS")
		)
		(fp_line
			(start 0 0.381)
			(end 0 -0.381)
			(stroke
				(width 0.1524)
				(type default)
			)
			(layer "F.SilkS")
		)
		(fp_line
			(start 0.7874 -0.4064)
			(end 0.7874 0.4064)
			(stroke
				(width 0.1524)
				(type default)
			)
			(layer "F.SilkS")
		)
		(fp_line
			(start 0.7874 0.4064)
			(end -0.7874 0.4064)
			(stroke
				(width 0.1524)
				(type default)
			)
			(layer "F.SilkS")
		)
		(fp_poly
			(pts
				(xy -0.5334 0.254) (xy -0.635 0.254) (xy -0.635 0.2286) (xy -0.635 -0.254) (xy -0.5334 -0.254) (xy -0.5334 -0.2794)
				(xy 0.5334 -0.2794) (xy 0.5334 -0.254) (xy 0.635 -0.254) (xy 0.635 0.254) (xy 0.5334 0.254) (xy 0.5334 0.2794)
				(xy -0.508 0.2794) (xy -0.5334 0.2794)
			)
			(stroke
				(width 0)
				(type default)
			)
			(fill no)
			(layer "F.CrtYd")
		)
		(pad "1" smd rect
			(at 0.40005 0)
			(size 0.4572 0.508)
			(layers "F.Cu" "F.Mask" "F.Paste")
			(net "P3V3_NODE1")
		)
		(pad "2" smd rect
			(at -0.40005 0)
			(size 0.4572 0.508)
			(layers "F.Cu" "F.Mask" "F.Paste")
			(net "GND")
		)
	)
)
